(kicad_pcb
	(version 20260206)
	(generator "pcbnew")
	(generator_version "10.0")
	(general
		(thickness 1.6)
		(legacy_teardrops no)
	)
	(paper "A4")
	(title_block
		(title "04192023_DAF0TMB3IC0_F0TG_MB_C_brd_V02_OCP.brd")
		(comment 1 "Grand Teton / footprints 5098-5104 of 8354")
	)
	(layers
		(0 "F.Cu" signal "TOP")
		(4 "In1.Cu" signal "GND")
		(6 "In2.Cu" signal "IN1")
		(8 "In3.Cu" signal "GND1")
		(10 "In4.Cu" signal "IN2")
		(12 "In5.Cu" signal "GND2")
		(14 "In6.Cu" signal "IN3")
		(16 "In7.Cu" signal "GND3")
		(18 "In8.Cu" signal "VCC")
		(20 "In9.Cu" signal "VCC1")
		(22 "In10.Cu" signal "GND4")
		(24 "In11.Cu" signal "IN4")
		(26 "In12.Cu" signal "GND5")
		(28 "In13.Cu" signal "IN5")
		(30 "In14.Cu" signal "GND6")
		(32 "In15.Cu" signal "IN6")
		(34 "In16.Cu" signal "GND7")
		(2 "B.Cu" signal "BOTTOM")
		(9 "F.Adhes" user "F.Adhesive")
		(11 "B.Adhes" user "B.Adhesive")
		(13 "F.Paste" user "Package Geometry/Pastemask Top")
		(15 "B.Paste" user "Package Geometry/Pastemask Bottom")
		(5 "F.SilkS" user "Ref Des/Silkscreen Top")
		(7 "B.SilkS" user "Ref Des/Silkscreen Bottom")
		(1 "F.Mask" user "Board Geometry/Soldermask Top")
		(3 "B.Mask" user "Board Geometry/Soldermask Bottom")
		(17 "Dwgs.User" user "User.Drawings")
		(19 "Cmts.User" user "User.Comments")
		(21 "Eco1.User" user "User.Eco1")
		(23 "Eco2.User" user "User.Eco2")
		(25 "Edge.Cuts" user "Board Geometry/Outline")
		(27 "Margin" user)
		(31 "F.CrtYd" user "Package Geometry/Place Bound Top")
		(29 "B.CrtYd" user "Package Geometry/Place Bound Bottom")
		(35 "F.Fab" user "Ref Des/Assembly Top")
		(33 "B.Fab" user "Ref Des/Assembly Bottom")
	)
	(footprint ""
		(layer "B.Cu")
		(at 319.467484 -335.063084 90)
		(property "Reference" "PC120_3"
			(at 0 0 90)
			(layer "B.SilkS")
			(hide yes)
			(effects
				(font
					(size 1.27 1.27)
				)
				(justify mirror)
			)
		)
		(property "Value" ""
			(at 0 0 90)
			(layer "B.Fab")
			(effects
				(font
					(size 1.27 1.27)
				)
				(justify mirror)
			)
		)
		(duplicate_pad_numbers_are_jumpers no)
		(fp_line
			(start 1.524 -0.762)
			(end -1.524 -0.762)
			(stroke
				(width 0.1524)
				(type default)
			)
			(layer "B.SilkS")
		)
		(fp_line
			(start -1.524 -0.762)
			(end -1.524 0.762)
			(stroke
				(width 0.1524)
				(type default)
			)
			(layer "B.SilkS")
		)
		(fp_line
			(start 1.524 0.762)
			(end 1.524 -0.762)
			(stroke
				(width 0.1524)
				(type default)
			)
			(layer "B.SilkS")
		)
		(fp_line
			(start -1.524 0.762)
			(end 1.524 0.762)
			(stroke
				(width 0.1524)
				(type default)
			)
			(layer "B.SilkS")
		)
		(fp_line
			(start 1.1049 -0.724916)
			(end 1.1049 0.724916)
			(stroke
				(width 0.1)
				(type default)
			)
			(layer "B.Fab")
		)
		(fp_line
			(start -1.1049 -0.724916)
			(end 1.1049 -0.724916)
			(stroke
				(width 0.1)
				(type default)
			)
			(layer "B.Fab")
		)
		(fp_line
			(start 1.1049 0.724916)
			(end -1.1049 0.724916)
			(stroke
				(width 0.1)
				(type default)
			)
			(layer "B.Fab")
		)
		(fp_line
			(start -1.1049 0.724916)
			(end -1.1049 -0.724916)
			(stroke
				(width 0.1)
				(type default)
			)
			(layer "B.Fab")
		)
		(pad "1" smd rect
			(at 0.889 0 90)
			(size 1.016 1.27)
			(layers "B.Cu" "B.Mask" "B.Paste")
			(net "SW_P12V_AUX_PVDDCR_CPU1_P0_FLT")
		)
		(pad "2" smd rect
			(at -0.889 0 90)
			(size 1.016 1.27)
			(layers "B.Cu" "B.Mask" "B.Paste")
			(net "GND")
		)
	)
	(footprint ""
		(layer "B.Cu")
		(at 158.440628 -16.553942 180)
		(property "Reference" "R331"
			(at 0 0 0)
			(layer "B.SilkS")
			(hide yes)
			(effects
				(font
					(size 1.27 1.27)
				)
				(justify mirror)
			)
		)
		(property "Value" ""
			(at 0 0 0)
			(layer "B.Fab")
			(effects
				(font
					(size 1.27 1.27)
				)
				(justify mirror)
			)
		)
		(duplicate_pad_numbers_are_jumpers no)
		(fp_line
			(start 0.7874 0.4064)
			(end 0.7874 -0.4064)
			(stroke
				(width 0.1524)
				(type default)
			)
			(layer "B.SilkS")
		)
		(fp_line
			(start 0.7874 -0.4064)
			(end -0.7874 -0.4064)
			(stroke
				(width 0.1524)
				(type default)
			)
			(layer "B.SilkS")
		)
		(fp_line
			(start -0.7874 0.4064)
			(end 0.7874 0.4064)
			(stroke
				(width 0.1524)
				(type default)
			)
			(layer "B.SilkS")
		)
		(fp_line
			(start -0.7874 -0.4064)
			(end -0.7874 0.4064)
			(stroke
				(width 0.1524)
				(type default)
			)
			(layer "B.SilkS")
		)
		(fp_line
			(start 0.67945 0.3048)
			(end 0.67945 -0.305054)
			(stroke
				(width 0.1)
				(type default)
			)
			(layer "B.Fab")
		)
		(fp_line
			(start 0.67945 -0.305054)
			(end 0.12065 -0.305054)
			(stroke
				(width 0.1)
				(type default)
			)
			(layer "B.Fab")
		)
		(fp_line
			(start 0.12065 0.3048)
			(end 0.67945 0.3048)
			(stroke
				(width 0.1)
				(type default)
			)
			(layer "B.Fab")
		)
		(fp_line
			(start 0.12065 0.2794)
			(end 0.12065 0.3048)
			(stroke
				(width 0.1)
				(type default)
			)
			(layer "B.Fab")
		)
		(fp_line
			(start 0.12065 -0.2794)
			(end -0.12065 -0.2794)
			(stroke
				(width 0.1)
				(type default)
			)
			(layer "B.Fab")
		)
		(fp_line
			(start 0.12065 -0.305054)
			(end 0.12065 -0.2794)
			(stroke
				(width 0.1)
				(type default)
			)
			(layer "B.Fab")
		)
		(fp_line
			(start -0.120396 0.3048)
			(end -0.120396 0.2794)
			(stroke
				(width 0.1)
				(type default)
			)
			(layer "B.Fab")
		)
		(fp_line
			(start -0.120396 0.2794)
			(end 0.12065 0.2794)
			(stroke
				(width 0.1)
				(type default)
			)
			(layer "B.Fab")
		)
		(fp_line
			(start -0.12065 -0.2794)
			(end -0.12065 -0.3048)
			(stroke
				(width 0.1)
				(type default)
			)
			(layer "B.Fab")
		)
		(fp_line
			(start -0.12065 -0.3048)
			(end -0.67945 -0.3048)
			(stroke
				(width 0.1)
				(type default)
			)
			(layer "B.Fab")
		)
		(fp_line
			(start -0.67945 0.3048)
			(end -0.120396 0.3048)
			(stroke
				(width 0.1)
				(type default)
			)
			(layer "B.Fab")
		)
		(fp_line
			(start -0.67945 -0.3048)
			(end -0.67945 0.3048)
			(stroke
				(width 0.1)
				(type default)
			)
			(layer "B.Fab")
		)
		(pad "1" smd circle
			(at 0.40005 0)
			(size 0 0)
			(layers "B.Cu" "B.Mask" "B.Paste")
			(net "SMB_FAN_3V3AUX_SDA")
		)
		(pad "2" smd circle
			(at -0.40005 0)
			(size 0 0)
			(layers "B.Cu" "B.Mask" "B.Paste")
			(net "P3V3_AUX")
		)
	)
	(footprint ""
		(layer "B.Cu")
		(at 180.271928 -193.996564)
		(property "Reference" "R112"
			(at 0 0 0)
			(layer "B.SilkS")
			(hide yes)
			(effects
				(font
					(size 1.27 1.27)
				)
				(justify mirror)
			)
		)
		(property "Value" ""
			(at 0 0 0)
			(layer "B.Fab")
			(effects
				(font
					(size 1.27 1.27)
				)
				(justify mirror)
			)
		)
		(duplicate_pad_numbers_are_jumpers no)
		(fp_line
			(start -0.7874 -0.4064)
			(end -0.7874 0.4064)
			(stroke
				(width 0.1524)
				(type default)
			)
			(layer "B.SilkS")
		)
		(fp_line
			(start -0.7874 0.4064)
			(end 0.7874 0.4064)
			(stroke
				(width 0.1524)
				(type default)
			)
			(layer "B.SilkS")
		)
		(fp_line
			(start 0.7874 -0.4064)
			(end -0.7874 -0.4064)
			(stroke
				(width 0.1524)
				(type default)
			)
			(layer "B.SilkS")
		)
		(fp_line
			(start 0.7874 0.4064)
			(end 0.7874 -0.4064)
			(stroke
				(width 0.1524)
				(type default)
			)
			(layer "B.SilkS")
		)
		(fp_line
			(start -0.67945 -0.3048)
			(end -0.67945 0.3048)
			(stroke
				(width 0.1)
				(type default)
			)
			(layer "B.Fab")
		)
		(fp_line
			(start -0.67945 0.3048)
			(end -0.120396 0.3048)
			(stroke
				(width 0.1)
				(type default)
			)
			(layer "B.Fab")
		)
		(fp_line
			(start -0.12065 -0.3048)
			(end -0.67945 -0.3048)
			(stroke
				(width 0.1)
				(type default)
			)
			(layer "B.Fab")
		)
		(fp_line
			(start -0.12065 -0.2794)
			(end -0.12065 -0.3048)
			(stroke
				(width 0.1)
				(type default)
			)
			(layer "B.Fab")
		)
		(fp_line
			(start -0.120396 0.2794)
			(end 0.12065 0.2794)
			(stroke
				(width 0.1)
				(type default)
			)
			(layer "B.Fab")
		)
		(fp_line
			(start -0.120396 0.3048)
			(end -0.120396 0.2794)
			(stroke
				(width 0.1)
				(type default)
			)
			(layer "B.Fab")
		)
		(fp_line
			(start 0.12065 -0.305054)
			(end 0.12065 -0.2794)
			(stroke
				(width 0.1)
				(type default)
			)
			(layer "B.Fab")
		)
		(fp_line
			(start 0.12065 -0.2794)
			(end -0.12065 -0.2794)
			(stroke
				(width 0.1)
				(type default)
			)
			(layer "B.Fab")
		)
		(fp_line
			(start 0.12065 0.2794)
			(end 0.12065 0.3048)
			(stroke
				(width 0.1)
				(type default)
			)
			(layer "B.Fab")
		)
		(fp_line
			(start 0.12065 0.3048)
			(end 0.67945 0.3048)
			(stroke
				(width 0.1)
				(type default)
			)
			(layer "B.Fab")
		)
		(fp_line
			(start 0.67945 -0.305054)
			(end 0.12065 -0.305054)
			(stroke
				(width 0.1)
				(type default)
			)
			(layer "B.Fab")
		)
		(fp_line
			(start 0.67945 0.3048)
			(end 0.67945 -0.305054)
			(stroke
				(width 0.1)
				(type default)
			)
			(layer "B.Fab")
		)
		(pad "1" smd circle
			(at 0.40005 0 180)
			(size 0 0)
			(layers "B.Cu" "B.Mask" "B.Paste")
			(net "P3V3")
		)
		(pad "2" smd circle
			(at -0.40005 0 180)
			(size 0 0)
			(layers "B.Cu" "B.Mask" "B.Paste")
			(net "PWRGD_CHI_CPU1_DIMM")
		)
	)
	(footprint ""
		(layer "B.Cu")
		(at 208.461356 -386.152136)
		(property "Reference" "PR2516"
			(at 0 0 0)
			(layer "B.SilkS")
			(hide yes)
			(effects
				(font
					(size 1.27 1.27)
				)
				(justify mirror)
			)
		)
		(property "Value" ""
			(at 0 0 0)
			(layer "B.Fab")
			(effects
				(font
					(size 1.27 1.27)
				)
				(justify mirror)
			)
		)
		(duplicate_pad_numbers_are_jumpers no)
		(fp_line
			(start -0.7874 -0.4064)
			(end -0.7874 0.4064)
			(stroke
				(width 0.1524)
				(type default)
			)
			(layer "B.SilkS")
		)
		(fp_line
			(start -0.7874 0.4064)
			(end 0.7874 0.4064)
			(stroke
				(width 0.1524)
				(type default)
			)
			(layer "B.SilkS")
		)
		(fp_line
			(start 0.7874 -0.4064)
			(end -0.7874 -0.4064)
			(stroke
				(width 0.1524)
				(type default)
			)
			(layer "B.SilkS")
		)
		(fp_line
			(start 0.7874 0.4064)
			(end 0.7874 -0.4064)
			(stroke
				(width 0.1524)
				(type default)
			)
			(layer "B.SilkS")
		)
		(fp_line
			(start -0.67945 -0.3048)
			(end -0.67945 0.3048)
			(stroke
				(width 0.1)
				(type default)
			)
			(layer "B.Fab")
		)
		(fp_line
			(start -0.67945 0.3048)
			(end -0.120396 0.3048)
			(stroke
				(width 0.1)
				(type default)
			)
			(layer "B.Fab")
		)
		(fp_line
			(start -0.12065 -0.3048)
			(end -0.67945 -0.3048)
			(stroke
				(width 0.1)
				(type default)
			)
			(layer "B.Fab")
		)
		(fp_line
			(start -0.12065 -0.2794)
			(end -0.12065 -0.3048)
			(stroke
				(width 0.1)
				(type default)
			)
			(layer "B.Fab")
		)
		(fp_line
			(start -0.120396 0.2794)
			(end 0.12065 0.2794)
			(stroke
				(width 0.1)
				(type default)
			)
			(layer "B.Fab")
		)
		(fp_line
			(start -0.120396 0.3048)
			(end -0.120396 0.2794)
			(stroke
				(width 0.1)
				(type default)
			)
			(layer "B.Fab")
		)
		(fp_line
			(start 0.12065 -0.305054)
			(end 0.12065 -0.2794)
			(stroke
				(width 0.1)
				(type default)
			)
			(layer "B.Fab")
		)
		(fp_line
			(start 0.12065 -0.2794)
			(end -0.12065 -0.2794)
			(stroke
				(width 0.1)
				(type default)
			)
			(layer "B.Fab")
		)
		(fp_line
			(start 0.12065 0.2794)
			(end 0.12065 0.3048)
			(stroke
				(width 0.1)
				(type default)
			)
			(layer "B.Fab")
		)
		(fp_line
			(start 0.12065 0.3048)
			(end 0.67945 0.3048)
			(stroke
				(width 0.1)
				(type default)
			)
			(layer "B.Fab")
		)
		(fp_line
			(start 0.67945 -0.305054)
			(end 0.12065 -0.305054)
			(stroke
				(width 0.1)
				(type default)
			)
			(layer "B.Fab")
		)
		(fp_line
			(start 0.67945 0.3048)
			(end 0.67945 -0.305054)
			(stroke
				(width 0.1)
				(type default)
			)
			(layer "B.Fab")
		)
		(pad "1" smd circle
			(at 0.40005 0 180)
			(size 0 0)
			(layers "B.Cu" "B.Mask" "B.Paste")
			(net "P12V_HSC_ADC_N")
		)
		(pad "2" smd circle
			(at -0.40005 0 180)
			(size 0 0)
			(layers "B.Cu" "B.Mask" "B.Paste")
			(net "P12V_HSC_SENSE2_R2_N")
		)
	)
	(footprint ""
		(layer "B.Cu")
		(at 254.635 -335.13268 180)
		(property "Reference" "R1382"
			(at 0 0 0)
			(layer "B.SilkS")
			(hide yes)
			(effects
				(font
					(size 1.27 1.27)
				)
				(justify mirror)
			)
		)
		(property "Value" ""
			(at 0 0 0)
			(layer "B.Fab")
			(effects
				(font
					(size 1.27 1.27)
				)
				(justify mirror)
			)
		)
		(duplicate_pad_numbers_are_jumpers no)
		(fp_line
			(start 0.32512 0.175006)
			(end 0.32512 -0.175006)
			(stroke
				(width 0.1)
				(type default)
			)
			(layer "B.Fab")
		)
		(fp_line
			(start 0.32512 -0.175006)
			(end -0.32512 -0.175006)
			(stroke
				(width 0.1)
				(type default)
			)
			(layer "B.Fab")
		)
		(fp_line
			(start -0.32512 0.175006)
			(end 0.32512 0.175006)
			(stroke
				(width 0.1)
				(type default)
			)
			(layer "B.Fab")
		)
		(fp_line
			(start -0.32512 -0.175006)
			(end -0.32512 0.175006)
			(stroke
				(width 0.1)
				(type default)
			)
			(layer "B.Fab")
		)
		(pad "1" smd rect
			(at 0.2667 0)
			(size 0.3048 0.381)
			(layers "B.Cu" "B.Mask" "B.Paste")
			(net "P1V8_CPU0_RT_1D")
		)
		(pad "2" smd rect
			(at -0.2667 0 180)
			(size 0.3048 0.381)
			(layers "B.Cu" "B.Mask" "B.Paste")
			(net "SMB_RT_CPU0_P2_ROM_MUX_2D_R_SDA")
		)
	)
	(footprint ""
		(layer "B.Cu")
		(at 418.191188 -161.102548 90)
		(property "Reference" "PR367"
			(at 0 0 90)
			(layer "B.SilkS")
			(hide yes)
			(effects
				(font
					(size 1.27 1.27)
				)
				(justify mirror)
			)
		)
		(property "Value" ""
			(at 0 0 90)
			(layer "B.Fab")
			(effects
				(font
					(size 1.27 1.27)
				)
				(justify mirror)
			)
		)
		(duplicate_pad_numbers_are_jumpers no)
		(fp_line
			(start 0.7874 -0.4064)
			(end -0.7874 -0.4064)
			(stroke
				(width 0.1524)
				(type default)
			)
			(layer "B.SilkS")
		)
		(fp_line
			(start -0.7874 -0.4064)
			(end -0.7874 0.4064)
			(stroke
				(width 0.1524)
				(type default)
			)
			(layer "B.SilkS")
		)
		(fp_line
			(start 0.7874 0.4064)
			(end 0.7874 -0.4064)
			(stroke
				(width 0.1524)
				(type default)
			)
			(layer "B.SilkS")
		)
		(fp_line
			(start -0.7874 0.4064)
			(end 0.7874 0.4064)
			(stroke
				(width 0.1524)
				(type default)
			)
			(layer "B.SilkS")
		)
		(fp_line
			(start 0.67945 -0.305054)
			(end 0.12065 -0.305054)
			(stroke
				(width 0.1)
				(type default)
			)
			(layer "B.Fab")
		)
		(fp_line
			(start 0.12065 -0.305054)
			(end 0.12065 -0.2794)
			(stroke
				(width 0.1)
				(type default)
			)
			(layer "B.Fab")
		)
		(fp_line
			(start -0.12065 -0.3048)
			(end -0.67945 -0.3048)
			(stroke
				(width 0.1)
				(type default)
			)
			(layer "B.Fab")
		)
		(fp_line
			(start -0.67945 -0.3048)
			(end -0.67945 0.3048)
			(stroke
				(width 0.1)
				(type default)
			)
			(layer "B.Fab")
		)
		(fp_line
			(start 0.12065 -0.2794)
			(end -0.12065 -0.2794)
			(stroke
				(width 0.1)
				(type default)
			)
			(layer "B.Fab")
		)
		(fp_line
			(start -0.12065 -0.2794)
			(end -0.12065 -0.3048)
			(stroke
				(width 0.1)
				(type default)
			)
			(layer "B.Fab")
		)
		(fp_line
			(start 0.12065 0.2794)
			(end 0.12065 0.3048)
			(stroke
				(width 0.1)
				(type default)
			)
			(layer "B.Fab")
		)
		(fp_line
			(start -0.120396 0.2794)
			(end 0.12065 0.2794)
			(stroke
				(width 0.1)
				(type default)
			)
			(layer "B.Fab")
		)
		(fp_line
			(start 0.67945 0.3048)
			(end 0.67945 -0.305054)
			(stroke
				(width 0.1)
				(type default)
			)
			(layer "B.Fab")
		)
		(fp_line
			(start 0.12065 0.3048)
			(end 0.67945 0.3048)
			(stroke
				(width 0.1)
				(type default)
			)
			(layer "B.Fab")
		)
		(fp_line
			(start -0.120396 0.3048)
			(end -0.120396 0.2794)
			(stroke
				(width 0.1)
				(type default)
			)
			(layer "B.Fab")
		)
		(fp_line
			(start -0.67945 0.3048)
			(end -0.120396 0.3048)
			(stroke
				(width 0.1)
				(type default)
			)
			(layer "B.Fab")
		)
		(pad "1" smd circle
			(at 0.40005 0 270)
			(size 0 0)
			(layers "B.Cu" "B.Mask" "B.Paste")
			(net "PVDDCR_SOC_P0_VOS3")
		)
		(pad "2" smd circle
			(at -0.40005 0 270)
			(size 0 0)
			(layers "B.Cu" "B.Mask" "B.Paste")
			(net "PVDDCR_SOC_P0")
		)
	)
	(footprint ""
		(layer "B.Cu")
		(at 62.752732 -338.091272 -90)
		(property "Reference" "PC420_4"
			(at 0 0 90)
			(layer "B.SilkS")
			(hide yes)
			(effects
				(font
					(size 1.27 1.27)
				)
				(justify mirror)
			)
		)
		(property "Value" ""
			(at 0 0 90)
			(layer "B.Fab")
			(effects
				(font
					(size 1.27 1.27)
				)
				(justify mirror)
			)
		)
		(duplicate_pad_numbers_are_jumpers no)
		(fp_line
			(start -1.524 0.762)
			(end 1.524 0.762)
			(stroke
				(width 0.1524)
				(type default)
			)
			(layer "B.SilkS")
		)
		(fp_line
			(start 1.524 0.762)
			(end 1.524 -0.762)
			(stroke
				(width 0.1524)
				(type default)
			)
			(layer "B.SilkS")
		)
		(fp_line
			(start -1.524 -0.762)
			(end -1.524 0.762)
			(stroke
				(width 0.1524)
				(type default)
			)
			(layer "B.SilkS")
		)
		(fp_line
			(start 1.524 -0.762)
			(end -1.524 -0.762)
			(stroke
				(width 0.1524)
				(type default)
			)
			(layer "B.SilkS")
		)
		(fp_line
			(start -1.1049 0.724916)
			(end -1.1049 -0.724916)
			(stroke
				(width 0.1)
				(type default)
			)
			(layer "B.Fab")
		)
		(fp_line
			(start 1.1049 0.724916)
			(end -1.1049 0.724916)
			(stroke
				(width 0.1)
				(type default)
			)
			(layer "B.Fab")
		)
		(fp_line
			(start -1.1049 -0.724916)
			(end 1.1049 -0.724916)
			(stroke
				(width 0.1)
				(type default)
			)
			(layer "B.Fab")
		)
		(fp_line
			(start 1.1049 -0.724916)
			(end 1.1049 0.724916)
			(stroke
				(width 0.1)
				(type default)
			)
			(layer "B.Fab")
		)
		(pad "1" smd rect
			(at 0.889 0 270)
			(size 1.016 1.27)
			(layers "B.Cu" "B.Mask" "B.Paste")
			(net "PVDDCR_CPU1_P1")
		)
		(pad "2" smd rect
			(at -0.889 0 270)
			(size 1.016 1.27)
			(layers "B.Cu" "B.Mask" "B.Paste")
			(net "GND")
		)
	)
)
